# S9S_MB_2U (Grand Teton) — schematic netlist excerpt (pin names and nets, part order shuffled) for the footprints in the layout excerpt that follows; sources: Cadence DE-HDL packaged netlist, KiCad conversion of 03242023_DA0F0TMBIJ0_F0T_Motherboard_J_brd_V01_OCP.brd

R4722  Q_RES  10K 1% CHIP  pkg 0402LF  page 184 : A = FM_PCH_BMC_RST_R_N ; B = P3V3_AUX

Q104  MOSFET_NCH_DUAL  PJT138K IC  pkg SOT363XD  page 147
  S1  = GND
  G1  = GPU_FPGA_OVERT_N
  D2  = GPU_FPGA_OVERT_ISO_N
  S2  = GND
  G2  = GPU_FPGA_OVERT
  D1  = GPU_FPGA_OVERT

(kicad_pcb
	(version 20260206)
	(generator "pcbnew")
	(generator_version "10.0")
	(general
		(thickness 1.6)
		(legacy_teardrops no)
	)
	(paper "A4")
	(title_block
		(title "03242023_DA0F0TMBIJ0_F0T_Motherboard_J_brd_V01_OCP.brd")
		(comment 1 "Grand Teton / footprints 1315-1316 of 6105")
	)
	(layers
		(0 "F.Cu" signal "TOP")
		(4 "In1.Cu" signal "GND")
		(6 "In2.Cu" signal "IN1")
		(8 "In3.Cu" signal "GND1")
		(10 "In4.Cu" signal "IN2")
		(12 "In5.Cu" signal "GND2")
		(14 "In6.Cu" signal "IN3")
		(16 "In7.Cu" signal "GND3")
		(18 "In8.Cu" signal "VCC")
		(20 "In9.Cu" signal "VCC1")
		(22 "In10.Cu" signal "GND4")
		(24 "In11.Cu" signal "IN4")
		(26 "In12.Cu" signal "GND5")
		(28 "In13.Cu" signal "IN5")
		(30 "In14.Cu" signal "GND6")
		(32 "In15.Cu" signal "IN6")
		(34 "In16.Cu" signal "GND7")
		(2 "B.Cu" signal "BOTTOM")
		(9 "F.Adhes" user "F.Adhesive")
		(11 "B.Adhes" user "B.Adhesive")
		(13 "F.Paste" user "Package Geometry/Pastemask Top")
		(15 "B.Paste" user "Package Geometry/Pastemask Bottom")
		(5 "F.SilkS" user "Ref Des/Silkscreen Top")
		(7 "B.SilkS" user "Ref Des/Silkscreen Bottom")
		(1 "F.Mask" user "Board Geometry/Soldermask Top")
		(3 "B.Mask" user "Board Geometry/Soldermask Bottom")
		(17 "Dwgs.User" user "User.Drawings")
		(19 "Cmts.User" user "User.Comments")
		(21 "Eco1.User" user "User.Eco1")
		(23 "Eco2.User" user "User.Eco2")
		(25 "Edge.Cuts" user "Board Geometry/Outline")
		(27 "Margin" user)
		(31 "F.CrtYd" user "Package Geometry/Place Bound Top")
		(29 "B.CrtYd" user "Package Geometry/Place Bound Bottom")
		(35 "F.Fab" user "Ref Des/Assembly Top")
		(33 "B.Fab" user "Ref Des/Assembly Bottom")
	)
	(footprint ""
		(layer "F.Cu")
		(at 204.99578 -112.02924 180)
		(property "Reference" "R4722"
			(at 0 0 180)
			(layer "F.SilkS")
			(hide yes)
			(effects
				(font
					(size 1.27 1.27)
				)
			)
		)
		(property "Value" ""
			(at 0 0 180)
			(layer "F.Fab")
			(effects
				(font
					(size 1.27 1.27)
				)
			)
		)
		(duplicate_pad_numbers_are_jumpers no)
		(fp_line
			(start 0.7874 0.4064)
			(end -0.7874 0.4064)
			(stroke
				(width 0.1524)
				(type default)
			)
			(layer "F.SilkS")
		)
		(fp_line
			(start 0.7874 -0.4064)
			(end 0.7874 0.4064)
			(stroke
				(width 0.1524)
				(type default)
			)
			(layer "F.SilkS")
		)
		(fp_line
			(start -0.7874 0.4064)
			(end -0.7874 -0.4064)
			(stroke
				(width 0.1524)
				(type default)
			)
			(layer "F.SilkS")
		)
		(fp_line
			(start -0.7874 -0.4064)
			(end 0.7874 -0.4064)
			(stroke
				(width 0.1524)
				(type default)
			)
			(layer "F.SilkS")
		)
		(fp_line
			(start 0.67945 0.3048)
			(end 0.120396 0.3048)
			(stroke
				(width 0.1)
				(type default)
			)
			(layer "F.Fab")
		)
		(fp_line
			(start 0.67945 -0.3048)
			(end 0.67945 0.3048)
			(stroke
				(width 0.1)
				(type default)
			)
			(layer "F.Fab")
		)
		(fp_line
			(start 0.12065 -0.2794)
			(end 0.12065 -0.3048)
			(stroke
				(width 0.1)
				(type default)
			)
			(layer "F.Fab")
		)
		(fp_line
			(start 0.12065 -0.3048)
			(end 0.67945 -0.3048)
			(stroke
				(width 0.1)
				(type default)
			)
			(layer "F.Fab")
		)
		(fp_line
			(start 0.120396 0.3048)
			(end 0.120396 0.2794)
			(stroke
				(width 0.1)
				(type default)
			)
			(layer "F.Fab")
		)
		(fp_line
			(start 0.120396 0.2794)
			(end -0.12065 0.2794)
			(stroke
				(width 0.1)
				(type default)
			)
			(layer "F.Fab")
		)
		(fp_line
			(start -0.12065 0.3048)
			(end -0.67945 0.3048)
			(stroke
				(width 0.1)
				(type default)
			)
			(layer "F.Fab")
		)
		(fp_line
			(start -0.12065 0.2794)
			(end -0.12065 0.3048)
			(stroke
				(width 0.1)
				(type default)
			)
			(layer "F.Fab")
		)
		(fp_line
			(start -0.12065 -0.2794)
			(end 0.12065 -0.2794)
			(stroke
				(width 0.1)
				(type default)
			)
			(layer "F.Fab")
		)
		(fp_line
			(start -0.12065 -0.305054)
			(end -0.12065 -0.2794)
			(stroke
				(width 0.1)
				(type default)
			)
			(layer "F.Fab")
		)
		(fp_line
			(start -0.67945 0.3048)
			(end -0.67945 -0.305054)
			(stroke
				(width 0.1)
				(type default)
			)
			(layer "F.Fab")
		)
		(fp_line
			(start -0.67945 -0.305054)
			(end -0.12065 -0.305054)
			(stroke
				(width 0.1)
				(type default)
			)
			(layer "F.Fab")
		)
		(pad "1" smd circle
			(at -0.40005 0 180)
			(size 0 0)
			(layers "F.Cu" "F.Mask" "F.Paste")
			(net "FM_PCH_BMC_RST_R_N")
		)
		(pad "2" smd circle
			(at 0.40005 0 180)
			(size 0 0)
			(layers "F.Cu" "F.Mask" "F.Paste")
			(net "P3V3_AUX")
		)
	)
	(footprint ""
		(layer "F.Cu")
		(at 428.179992 -396.448534)
		(property "Reference" "Q104"
			(at 0.079248 -1.848104 0)
			(unlocked yes)
			(layer "F.SilkS")
			(effects
				(font
					(size 0.7874 0.5842)
					(thickness 0.1524)
				)
				(justify left)
			)
		)
		(property "Value" ""
			(at 0 0 0)
			(layer "F.Fab")
			(effects
				(font
					(size 1.27 1.27)
				)
			)
		)
		(duplicate_pad_numbers_are_jumpers no)
		(fp_line
			(start -1.332738 -1.100074)
			(end -0.4826 -1.100074)
			(stroke
				(width 0.1524)
				(type default)
			)
			(layer "F.SilkS")
		)
		(fp_line
			(start -1.332738 1.100074)
			(end -1.332738 -1.100074)
			(stroke
				(width 0.1524)
				(type default)
			)
			(layer "F.SilkS")
		)
		(fp_line
			(start -0.4826 -1.100074)
			(end 0 -0.541274)
			(stroke
				(width 0.1524)
				(type default)
			)
			(layer "F.SilkS")
		)
		(fp_line
			(start 0 -0.541274)
			(end 0.4826 -1.100074)
			(stroke
				(width 0.1524)
				(type default)
			)
			(layer "F.SilkS")
		)
		(fp_line
			(start 0.4826 -1.100074)
			(end 1.332738 -1.100074)
			(stroke
				(width 0.1524)
				(type default)
			)
			(layer "F.SilkS")
		)
		(fp_line
			(start 1.332738 -1.100074)
			(end 1.332738 1.100074)
			(stroke
				(width 0.1524)
				(type default)
			)
			(layer "F.SilkS")
		)
		(fp_line
			(start 1.332738 1.100074)
			(end -1.332738 1.100074)
			(stroke
				(width 0.1524)
				(type default)
			)
			(layer "F.SilkS")
		)
		(fp_poly
			(pts
				(xy -0.647192 -2.136902) (xy -0.99822 -1.434846) (xy -1.349248 -2.136902)
			)
			(stroke
				(width 0)
				(type default)
			)
			(fill yes)
			(layer "F.SilkS")
		)
		(fp_line
			(start -0.674878 -1.100074)
			(end 0.674878 -1.100074)
			(stroke
				(width 0.1)
				(type default)
			)
			(layer "F.Fab")
		)
		(fp_line
			(start -0.674878 1.100074)
			(end -0.674878 -1.100074)
			(stroke
				(width 0.1)
				(type default)
			)
			(layer "F.Fab")
		)
		(fp_line
			(start 0.674878 -1.100074)
			(end 0.674878 1.100074)
			(stroke
				(width 0.1)
				(type default)
			)
			(layer "F.Fab")
		)
		(fp_line
			(start 0.674878 1.100074)
			(end -0.674878 1.100074)
			(stroke
				(width 0.1)
				(type default)
			)
			(layer "F.Fab")
		)
		(fp_poly
			(pts
				(xy -2.2352 -0.298958) (xy -2.2352 -1.001014) (xy -1.533144 -0.649986)
			)
			(stroke
				(width 0)
				(type default)
			)
			(fill yes)
			(layer "F.Fab")
		)
		(pad "1" smd rect
			(at -0.94996 -0.649986 90)
			(size 0.4318 0.508)
			(layers "F.Cu" "F.Mask" "F.Paste")
			(net "GND")
		)
		(pad "2" smd rect
			(at -0.94996 0 90)
			(size 0.4318 0.508)
			(layers "F.Cu" "F.Mask" "F.Paste")
			(net "GPU_FPGA_OVERT_N")
		)
		(pad "3" smd rect
			(at -0.94996 0.649986 90)
			(size 0.4318 0.508)
			(layers "F.Cu" "F.Mask" "F.Paste")
			(net "GPU_FPGA_OVERT_ISO_N")
		)
		(pad "4" smd rect
			(at 0.94996 0.649986 90)
			(size 0.4318 0.508)
			(layers "F.Cu" "F.Mask" "F.Paste")
			(net "GND")
		)
		(pad "5" smd rect
			(at 0.94996 0 90)
			(size 0.4318 0.508)
			(layers "F.Cu" "F.Mask" "F.Paste")
			(net "GPU_FPGA_OVERT")
		)
		(pad "6" smd rect
			(at 0.94996 -0.649986 90)
			(size 0.4318 0.508)
			(layers "F.Cu" "F.Mask" "F.Paste")
			(net "GPU_FPGA_OVERT")
		)
	)
)
